# T6G (Grand Teton) — schematic netlist excerpt (pin names and nets, part order shuffled) for the footprints in the layout excerpt that follows; sources: Cadence DE-HDL packaged netlist, KiCad conversion of 04192023_DAF0TMB3IC0_F0TG_MB_C_brd_V02_OCP.brd

R113  Q_RES  1K 1% EMPTY  pkg 0402LF  page 107 : A = P3V3 ; B = PWRGD_CHJ_CPU1_DIMM
R1374  Q_RES  4.7K 5% CHIP  pkg 0201LF  page 185 : A = P1V8_CPU0_RT_1D ; B = SMB_RT_CPU0_P1_ROM_MUX_2D_R_SCL
C1019  Q_CAP  1UF 4V 20% X6S  pkg 0201  page 312 : A = P0V9_CPU0_RT3_2A ; B = GND

(kicad_pcb
	(version 20260206)
	(generator "pcbnew")
	(generator_version "10.0")
	(general
		(thickness 1.6)
		(legacy_teardrops no)
	)
	(paper "A4")
	(title_block
		(title "04192023_DAF0TMB3IC0_F0TG_MB_C_brd_V02_OCP.brd")
		(comment 1 "Grand Teton / footprints 7708-7710 of 8354")
	)
	(layers
		(0 "F.Cu" signal "TOP")
		(4 "In1.Cu" signal "GND")
		(6 "In2.Cu" signal "IN1")
		(8 "In3.Cu" signal "GND1")
		(10 "In4.Cu" signal "IN2")
		(12 "In5.Cu" signal "GND2")
		(14 "In6.Cu" signal "IN3")
		(16 "In7.Cu" signal "GND3")
		(18 "In8.Cu" signal "VCC")
		(20 "In9.Cu" signal "VCC1")
		(22 "In10.Cu" signal "GND4")
		(24 "In11.Cu" signal "IN4")
		(26 "In12.Cu" signal "GND5")
		(28 "In13.Cu" signal "IN5")
		(30 "In14.Cu" signal "GND6")
		(32 "In15.Cu" signal "IN6")
		(34 "In16.Cu" signal "GND7")
		(2 "B.Cu" signal "BOTTOM")
		(9 "F.Adhes" user "F.Adhesive")
		(11 "B.Adhes" user "B.Adhesive")
		(13 "F.Paste" user "Package Geometry/Pastemask Top")
		(15 "B.Paste" user "Package Geometry/Pastemask Bottom")
		(5 "F.SilkS" user "Ref Des/Silkscreen Top")
		(7 "B.SilkS" user "Ref Des/Silkscreen Bottom")
		(1 "F.Mask" user "Board Geometry/Soldermask Top")
		(3 "B.Mask" user "Board Geometry/Soldermask Bottom")
		(17 "Dwgs.User" user "User.Drawings")
		(19 "Cmts.User" user "User.Comments")
		(21 "Eco1.User" user "User.Eco1")
		(23 "Eco2.User" user "User.Eco2")
		(25 "Edge.Cuts" user "Board Geometry/Outline")
		(27 "Margin" user)
		(31 "F.CrtYd" user "Package Geometry/Place Bound Top")
		(29 "B.CrtYd" user "Package Geometry/Place Bound Bottom")
		(35 "F.Fab" user "Ref Des/Assembly Top")
		(33 "B.Fab" user "Ref Des/Assembly Bottom")
	)
	(footprint ""
		(layer "B.Cu")
		(at 187.815728 -193.996564)
		(property "Reference" "R113"
			(at 0 0 0)
			(layer "B.SilkS")
			(hide yes)
			(effects
				(font
					(size 1.27 1.27)
				)
				(justify mirror)
			)
		)
		(property "Value" ""
			(at 0 0 0)
			(layer "B.Fab")
			(effects
				(font
					(size 1.27 1.27)
				)
				(justify mirror)
			)
		)
		(duplicate_pad_numbers_are_jumpers no)
		(fp_line
			(start -0.7874 -0.4064)
			(end -0.7874 0.4064)
			(stroke
				(width 0.1524)
				(type default)
			)
			(layer "B.SilkS")
		)
		(fp_line
			(start -0.7874 0.4064)
			(end 0.7874 0.4064)
			(stroke
				(width 0.1524)
				(type default)
			)
			(layer "B.SilkS")
		)
		(fp_line
			(start 0.7874 -0.4064)
			(end -0.7874 -0.4064)
			(stroke
				(width 0.1524)
				(type default)
			)
			(layer "B.SilkS")
		)
		(fp_line
			(start 0.7874 0.4064)
			(end 0.7874 -0.4064)
			(stroke
				(width 0.1524)
				(type default)
			)
			(layer "B.SilkS")
		)
		(fp_line
			(start -0.67945 -0.3048)
			(end -0.67945 0.3048)
			(stroke
				(width 0.1)
				(type default)
			)
			(layer "B.Fab")
		)
		(fp_line
			(start -0.67945 0.3048)
			(end -0.120396 0.3048)
			(stroke
				(width 0.1)
				(type default)
			)
			(layer "B.Fab")
		)
		(fp_line
			(start -0.12065 -0.3048)
			(end -0.67945 -0.3048)
			(stroke
				(width 0.1)
				(type default)
			)
			(layer "B.Fab")
		)
		(fp_line
			(start -0.12065 -0.2794)
			(end -0.12065 -0.3048)
			(stroke
				(width 0.1)
				(type default)
			)
			(layer "B.Fab")
		)
		(fp_line
			(start -0.120396 0.2794)
			(end 0.12065 0.2794)
			(stroke
				(width 0.1)
				(type default)
			)
			(layer "B.Fab")
		)
		(fp_line
			(start -0.120396 0.3048)
			(end -0.120396 0.2794)
			(stroke
				(width 0.1)
				(type default)
			)
			(layer "B.Fab")
		)
		(fp_line
			(start 0.12065 -0.305054)
			(end 0.12065 -0.2794)
			(stroke
				(width 0.1)
				(type default)
			)
			(layer "B.Fab")
		)
		(fp_line
			(start 0.12065 -0.2794)
			(end -0.12065 -0.2794)
			(stroke
				(width 0.1)
				(type default)
			)
			(layer "B.Fab")
		)
		(fp_line
			(start 0.12065 0.2794)
			(end 0.12065 0.3048)
			(stroke
				(width 0.1)
				(type default)
			)
			(layer "B.Fab")
		)
		(fp_line
			(start 0.12065 0.3048)
			(end 0.67945 0.3048)
			(stroke
				(width 0.1)
				(type default)
			)
			(layer "B.Fab")
		)
		(fp_line
			(start 0.67945 -0.305054)
			(end 0.12065 -0.305054)
			(stroke
				(width 0.1)
				(type default)
			)
			(layer "B.Fab")
		)
		(fp_line
			(start 0.67945 0.3048)
			(end 0.67945 -0.305054)
			(stroke
				(width 0.1)
				(type default)
			)
			(layer "B.Fab")
		)
		(pad "1" smd circle
			(at 0.40005 0 180)
			(size 0 0)
			(layers "B.Cu" "B.Mask" "B.Paste")
			(net "P3V3")
		)
		(pad "2" smd circle
			(at -0.40005 0 180)
			(size 0 0)
			(layers "B.Cu" "B.Mask" "B.Paste")
			(net "PWRGD_CHJ_CPU1_DIMM")
		)
	)
	(footprint ""
		(layer "B.Cu")
		(at 388.478522 -395.148562 90)
		(property "Reference" "C1019"
			(at 0 0 90)
			(layer "B.SilkS")
			(hide yes)
			(effects
				(font
					(size 1.27 1.27)
				)
				(justify mirror)
			)
		)
		(property "Value" ""
			(at 0 0 90)
			(layer "B.Fab")
			(effects
				(font
					(size 1.27 1.27)
				)
				(justify mirror)
			)
		)
		(duplicate_pad_numbers_are_jumpers no)
		(fp_line
			(start 0.299974 -0.150114)
			(end -0.299974 -0.150114)
			(stroke
				(width 0.1)
				(type default)
			)
			(layer "B.Fab")
		)
		(fp_line
			(start -0.299974 -0.150114)
			(end -0.299974 0.150114)
			(stroke
				(width 0.1)
				(type default)
			)
			(layer "B.Fab")
		)
		(fp_line
			(start 0.299974 0.150114)
			(end 0.299974 -0.150114)
			(stroke
				(width 0.1)
				(type default)
			)
			(layer "B.Fab")
		)
		(fp_line
			(start -0.299974 0.150114)
			(end 0.299974 0.150114)
			(stroke
				(width 0.1)
				(type default)
			)
			(layer "B.Fab")
		)
		(pad "1" smd rect
			(at 0.2667 0 270)
			(size 0.3048 0.381)
			(layers "B.Cu" "B.Mask" "B.Paste")
			(net "P0V9_CPU0_RT3_2A")
		)
		(pad "2" smd rect
			(at -0.2667 0 270)
			(size 0.3048 0.381)
			(layers "B.Cu" "B.Mask" "B.Paste")
			(net "GND")
		)
	)
	(footprint ""
		(layer "B.Cu")
		(at 254.635 -338.51596 180)
		(property "Reference" "R1374"
			(at 0 0 0)
			(layer "B.SilkS")
			(hide yes)
			(effects
				(font
					(size 1.27 1.27)
				)
				(justify mirror)
			)
		)
		(property "Value" ""
			(at 0 0 0)
			(layer "B.Fab")
			(effects
				(font
					(size 1.27 1.27)
				)
				(justify mirror)
			)
		)
		(duplicate_pad_numbers_are_jumpers no)
		(fp_line
			(start 0.32512 0.175006)
			(end 0.32512 -0.175006)
			(stroke
				(width 0.1)
				(type default)
			)
			(layer "B.Fab")
		)
		(fp_line
			(start 0.32512 -0.175006)
			(end -0.32512 -0.175006)
			(stroke
				(width 0.1)
				(type default)
			)
			(layer "B.Fab")
		)
		(fp_line
			(start -0.32512 0.175006)
			(end 0.32512 0.175006)
			(stroke
				(width 0.1)
				(type default)
			)
			(layer "B.Fab")
		)
		(fp_line
			(start -0.32512 -0.175006)
			(end -0.32512 0.175006)
			(stroke
				(width 0.1)
				(type default)
			)
			(layer "B.Fab")
		)
		(pad "1" smd rect
			(at 0.2667 0)
			(size 0.3048 0.381)
			(layers "B.Cu" "B.Mask" "B.Paste")
			(net "P1V8_CPU0_RT_1D")
		)
		(pad "2" smd rect
			(at -0.2667 0 180)
			(size 0.3048 0.381)
			(layers "B.Cu" "B.Mask" "B.Paste")
			(net "SMB_RT_CPU0_P1_ROM_MUX_2D_R_SCL")
		)
	)
)
